# TIMECARD (Time Appliance Project (Time Card)) — schematic netlist excerpt (pin names and nets, part order shuffled) for the footprints in the layout excerpt that follows; sources: Cadence DE-HDL packaged netlist, KiCad conversion of R4006-B0001-02_R01.brd

R175  RESISTOR  33OHM 1%  pkg SMC_0402R_H016  page 16 : \1\ = PCIE_SMDAT ; \2\ = EEPROM_SDA
R467  RESISTOR  33OHM 1%  pkg SMC_0402R_H016  page 24 : \1\ = R_FT4232_TCK ; \2\ = FT4232_TCK_SCLK

(kicad_pcb
	(version 20260206)
	(generator "pcbnew")
	(generator_version "10.0")
	(general
		(thickness 1.6)
		(legacy_teardrops no)
	)
	(paper "A4")
	(title_block
		(title "timecard-production-celestica-r4006 — R4006-B0001-02_R01.brd")
		(comment 1 "Time Appliance Project (Time Card) / footprints 1005-1006 of 1113")
	)
	(layers
		(0 "F.Cu" signal "TOP")
		(4 "In1.Cu" signal "L02_GND1")
		(6 "In2.Cu" signal "L03_SIG1")
		(8 "In3.Cu" signal "L04_GND2")
		(10 "In4.Cu" signal "L05_VCC1")
		(12 "In5.Cu" signal "L06_VCC2")
		(14 "In6.Cu" signal "L07_GND3")
		(16 "In7.Cu" signal "L08_SIG2")
		(18 "In8.Cu" signal "L09_GND4")
		(2 "B.Cu" signal "BOTTOM")
		(9 "F.Adhes" user "F.Adhesive")
		(11 "B.Adhes" user "B.Adhesive")
		(13 "F.Paste" user "Package Geometry/Pastemask Top")
		(15 "B.Paste" user "Package Geometry/Pastemask Bottom")
		(5 "F.SilkS" user "Ref Des/Silkscreen Top")
		(7 "B.SilkS" user "Ref Des/Silkscreen Bottom")
		(1 "F.Mask" user "Board Geometry/Soldermask Top")
		(3 "B.Mask" user "Board Geometry/Soldermask Bottom")
		(17 "Dwgs.User" user "User.Drawings")
		(19 "Cmts.User" user "User.Comments")
		(21 "Eco1.User" user "User.Eco1")
		(23 "Eco2.User" user "User.Eco2")
		(25 "Edge.Cuts" user "Board Geometry/Outline")
		(27 "Margin" user)
		(31 "F.CrtYd" user "Package Geometry/Place Bound Top")
		(29 "B.CrtYd" user "Package Geometry/Place Bound Bottom")
		(35 "F.Fab" user "Ref Des/Assembly Top")
		(33 "B.Fab" user "Ref Des/Assembly Bottom")
	)
	(footprint ""
		(layer "B.Cu")
		(at 33.7693 -16.7132)
		(property "Reference" "R175"
			(at 0.7747 1.89357 0)
			(unlocked yes)
			(layer "B.SilkS")
			(effects
				(font
					(size 0.7874 0.5842)
					(thickness 0.1524)
				)
				(justify mirror)
			)
		)
		(property "Value" "VAL*"
			(at -0.02032 2.13233 0)
			(unlocked yes)
			(layer "B.Fab")
			(hide yes)
			(effects
				(font
					(size 0.7874 0.5842)
					(thickness 0.1524)
				)
				(justify mirror)
			)
		)
		(property "Tolerance" "TOL*"
			(at -0.044704 3.05435 0)
			(unlocked yes)
			(layer "Cmts.User")
			(hide yes)
			(effects
				(font
					(size 0.7874 0.5842)
					(thickness 0.1524)
				)
				(justify mirror)
			)
		)
		(property "User Part Number" "PARTNUM*"
			(at -0.02032 4.024884 0)
			(unlocked yes)
			(layer "Cmts.User")
			(hide yes)
			(effects
				(font
					(size 0.7874 0.5842)
					(thickness 0.1524)
				)
				(justify mirror)
			)
		)
		(property "Device Type" "RESISTOR-G155-133R0-01,33OHM,1%"
			(at -0.008382 1.210564 0)
			(unlocked yes)
			(layer "B.Fab")
			(hide yes)
			(effects
				(font
					(size 0.7874 0.5842)
					(thickness 0.1524)
				)
				(justify mirror)
			)
		)
		(duplicate_pad_numbers_are_jumpers no)
		(fp_line
			(start -1.143 -0.5588)
			(end 1.143 -0.5588)
			(stroke
				(width 0.1)
				(type default)
			)
			(layer "B.SilkS")
		)
		(fp_line
			(start -1.143 0.5588)
			(end -1.143 -0.5588)
			(stroke
				(width 0.1)
				(type default)
			)
			(layer "B.SilkS")
		)
		(fp_line
			(start 1.143 -0.5588)
			(end 1.143 0.5588)
			(stroke
				(width 0.1)
				(type default)
			)
			(layer "B.SilkS")
		)
		(fp_line
			(start 1.143 0.5588)
			(end -1.143 0.5588)
			(stroke
				(width 0.1)
				(type default)
			)
			(layer "B.SilkS")
		)
		(fp_rect
			(start -1.143 0.5588)
			(end 1.143 -0.5588)
			(stroke
				(width 0)
				(type default)
			)
			(fill no)
			(layer "B.CrtYd")
		)
		(fp_line
			(start -0.508 -0.3048)
			(end 0.508 -0.3048)
			(stroke
				(width 0.1)
				(type default)
			)
			(layer "B.Fab")
		)
		(fp_line
			(start -0.508 0.3048)
			(end -0.508 -0.3048)
			(stroke
				(width 0.1)
				(type default)
			)
			(layer "B.Fab")
		)
		(fp_line
			(start 0.508 -0.3048)
			(end 0.508 0.3048)
			(stroke
				(width 0.1)
				(type default)
			)
			(layer "B.Fab")
		)
		(fp_line
			(start 0.508 0.3048)
			(end -0.508 0.3048)
			(stroke
				(width 0.1)
				(type default)
			)
			(layer "B.Fab")
		)
		(pad "1" smd rect
			(at 0.5334 0 180)
			(size 0.7112 0.6096)
			(layers "B.Cu" "B.Mask" "B.Paste")
			(net "PCIE_SMDAT")
		)
		(pad "2" smd rect
			(at -0.5334 0 180)
			(size 0.7112 0.6096)
			(layers "B.Cu" "B.Mask" "B.Paste")
			(net "EEPROM_SDA")
		)
		(zone
			(layer "B.Cu")
			(hatch none 0.5)
			(connect_pads
				(clearance 0)
			)
			(min_thickness 0.25)
			(keepout
				(tracks allowed)
				(vias not_allowed)
				(pads allowed)
				(copperpour not_allowed)
				(footprints allowed)
			)
			(placement
				(enabled no)
				(sheetname "")
			)
			(fill
				(thermal_gap 0.5)
				(thermal_bridge_width 0.5)
				(island_removal_mode 0)
			)
			(polygon
				(pts
					(xy 33.6931 -16.4084) (xy 33.8455 -16.4084) (xy 33.8455 -17.018) (xy 33.6931 -17.018)
				)
			)
		)
	)
	(footprint ""
		(layer "B.Cu")
		(at 24.13 -91.059 -90)
		(property "Reference" "R467"
			(at -2.286 5.11937 270)
			(unlocked yes)
			(layer "B.SilkS")
			(effects
				(font
					(size 0.7874 0.5842)
					(thickness 0.1524)
				)
				(justify mirror)
			)
		)
		(property "Value" "VAL*"
			(at -0.02032 2.13233 270)
			(unlocked yes)
			(layer "B.Fab")
			(hide yes)
			(effects
				(font
					(size 0.7874 0.5842)
					(thickness 0.1524)
				)
				(justify mirror)
			)
		)
		(property "Tolerance" "TOL*"
			(at -0.044704 3.05435 270)
			(unlocked yes)
			(layer "Cmts.User")
			(hide yes)
			(effects
				(font
					(size 0.7874 0.5842)
					(thickness 0.1524)
				)
				(justify mirror)
			)
		)
		(property "User Part Number" "PARTNUM*"
			(at -0.02032 4.024884 270)
			(unlocked yes)
			(layer "Cmts.User")
			(hide yes)
			(effects
				(font
					(size 0.7874 0.5842)
					(thickness 0.1524)
				)
				(justify mirror)
			)
		)
		(property "Device Type" "RESISTOR-G155-133R0-01,33OHM,1%"
			(at -0.008382 1.210564 270)
			(unlocked yes)
			(layer "B.Fab")
			(hide yes)
			(effects
				(font
					(size 0.7874 0.5842)
					(thickness 0.1524)
				)
				(justify mirror)
			)
		)
		(duplicate_pad_numbers_are_jumpers no)
		(fp_line
			(start -1.143 0.5588)
			(end -1.143 -0.5588)
			(stroke
				(width 0.1)
				(type default)
			)
			(layer "B.SilkS")
		)
		(fp_line
			(start 1.143 0.5588)
			(end -1.143 0.5588)
			(stroke
				(width 0.1)
				(type default)
			)
			(layer "B.SilkS")
		)
		(fp_line
			(start -1.143 -0.5588)
			(end 1.143 -0.5588)
			(stroke
				(width 0.1)
				(type default)
			)
			(layer "B.SilkS")
		)
		(fp_line
			(start 1.143 -0.5588)
			(end 1.143 0.5588)
			(stroke
				(width 0.1)
				(type default)
			)
			(layer "B.SilkS")
		)
		(fp_poly
			(pts
				(xy 1.143 0.5588) (xy -1.143 0.5588) (xy -1.143 -0.5588) (xy 1.143 -0.5588)
			)
			(stroke
				(width 0)
				(type default)
			)
			(fill no)
			(layer "B.CrtYd")
		)
		(fp_line
			(start -0.508 0.3048)
			(end -0.508 -0.3048)
			(stroke
				(width 0.1)
				(type default)
			)
			(layer "B.Fab")
		)
		(fp_line
			(start 0.508 0.3048)
			(end -0.508 0.3048)
			(stroke
				(width 0.1)
				(type default)
			)
			(layer "B.Fab")
		)
		(fp_line
			(start -0.508 -0.3048)
			(end 0.508 -0.3048)
			(stroke
				(width 0.1)
				(type default)
			)
			(layer "B.Fab")
		)
		(fp_line
			(start 0.508 -0.3048)
			(end 0.508 0.3048)
			(stroke
				(width 0.1)
				(type default)
			)
			(layer "B.Fab")
		)
		(pad "1" smd rect
			(at 0.5334 0 90)
			(size 0.7112 0.6096)
			(layers "B.Cu" "B.Mask" "B.Paste")
			(net "R_FT4232_TCK")
		)
		(pad "2" smd rect
			(at -0.5334 0 90)
			(size 0.7112 0.6096)
			(layers "B.Cu" "B.Mask" "B.Paste")
			(net "FT4232_TCK_SCLK")
		)
		(zone
			(layer "B.Cu")
			(hatch none 0.5)
			(connect_pads
				(clearance 0)
			)
			(min_thickness 0.25)
			(keepout
				(tracks allowed)
				(vias not_allowed)
				(pads allowed)
				(copperpour not_allowed)
				(footprints allowed)
			)
			(placement
				(enabled no)
				(sheetname "")
			)
			(fill
				(thermal_gap 0.5)
				(thermal_bridge_width 0.5)
				(island_removal_mode 0)
			)
			(polygon
				(pts
					(xy 23.8252 -90.9828) (xy 24.4348 -90.9828) (xy 24.4348 -91.1352) (xy 23.8252 -91.1352)
				)
			)
		)
		(zone
			(layer "B.Cu")
			(hatch none 0.5)
			(connect_pads
				(clearance 0)
			)
			(min_thickness 0.25)
			(keepout
				(tracks not_allowed)
				(vias allowed)
				(pads allowed)
				(copperpour not_allowed)
				(footprints allowed)
			)
			(placement
				(enabled no)
				(sheetname "")
			)
			(fill
				(thermal_gap 0.5)
				(thermal_bridge_width 0.5)
				(island_removal_mode 0)
			)
			(polygon
				(pts
					(xy 23.8252 -90.9828) (xy 24.4348 -90.9828) (xy 24.4348 -91.1352) (xy 23.8252 -91.1352)
				)
			)
		)
	)
)
